# T6G (Grand Teton) — schematic netlist excerpt (pin names and nets, part order shuffled) for the footprints in the layout excerpt that follows; sources: Cadence DE-HDL packaged netlist, KiCad conversion of 04192023_DAF0TMB3IC0_F0TG_MB_C_brd_V02_OCP.brd

R6273  Q_RES  200K 1% EMPTY  pkg 0402LF  page 178 : A = P3V3_AUX ; B = USB_HUB2_MRP_CFG_STRAP
R8113  Q_RES  10K 1% CHIP  pkg 0402LF  page 268 : A = P3V3_AUX ; B = UV_ADR_P2V5_COMP

(kicad_pcb
	(version 20260206)
	(generator "pcbnew")
	(generator_version "10.0")
	(general
		(thickness 1.6)
		(legacy_teardrops no)
	)
	(paper "A4")
	(title_block
		(title "04192023_DAF0TMB3IC0_F0TG_MB_C_brd_V02_OCP.brd")
		(comment 1 "Grand Teton / footprints 4862-4863 of 8354")
	)
	(layers
		(0 "F.Cu" signal "TOP")
		(4 "In1.Cu" signal "GND")
		(6 "In2.Cu" signal "IN1")
		(8 "In3.Cu" signal "GND1")
		(10 "In4.Cu" signal "IN2")
		(12 "In5.Cu" signal "GND2")
		(14 "In6.Cu" signal "IN3")
		(16 "In7.Cu" signal "GND3")
		(18 "In8.Cu" signal "VCC")
		(20 "In9.Cu" signal "VCC1")
		(22 "In10.Cu" signal "GND4")
		(24 "In11.Cu" signal "IN4")
		(26 "In12.Cu" signal "GND5")
		(28 "In13.Cu" signal "IN5")
		(30 "In14.Cu" signal "GND6")
		(32 "In15.Cu" signal "IN6")
		(34 "In16.Cu" signal "GND7")
		(2 "B.Cu" signal "BOTTOM")
		(9 "F.Adhes" user "F.Adhesive")
		(11 "B.Adhes" user "B.Adhesive")
		(13 "F.Paste" user "Package Geometry/Pastemask Top")
		(15 "B.Paste" user "Package Geometry/Pastemask Bottom")
		(5 "F.SilkS" user "Ref Des/Silkscreen Top")
		(7 "B.SilkS" user "Ref Des/Silkscreen Bottom")
		(1 "F.Mask" user "Board Geometry/Soldermask Top")
		(3 "B.Mask" user "Board Geometry/Soldermask Bottom")
		(17 "Dwgs.User" user "User.Drawings")
		(19 "Cmts.User" user "User.Comments")
		(21 "Eco1.User" user "User.Eco1")
		(23 "Eco2.User" user "User.Eco2")
		(25 "Edge.Cuts" user "Board Geometry/Outline")
		(27 "Margin" user)
		(31 "F.CrtYd" user "Package Geometry/Place Bound Top")
		(29 "B.CrtYd" user "Package Geometry/Place Bound Bottom")
		(35 "F.Fab" user "Ref Des/Assembly Top")
		(33 "B.Fab" user "Ref Des/Assembly Bottom")
	)
	(footprint ""
		(layer "F.Cu")
		(at 127.381 -106.934 90)
		(property "Reference" "R8113"
			(at 0 0 90)
			(layer "F.SilkS")
			(hide yes)
			(effects
				(font
					(size 1.27 1.27)
				)
			)
		)
		(property "Value" ""
			(at 0 0 90)
			(layer "F.Fab")
			(effects
				(font
					(size 1.27 1.27)
				)
			)
		)
		(duplicate_pad_numbers_are_jumpers no)
		(fp_line
			(start 0.7874 -0.4064)
			(end 0.7874 0.4064)
			(stroke
				(width 0.1524)
				(type default)
			)
			(layer "F.SilkS")
		)
		(fp_line
			(start -0.7874 -0.4064)
			(end 0.7874 -0.4064)
			(stroke
				(width 0.1524)
				(type default)
			)
			(layer "F.SilkS")
		)
		(fp_line
			(start 0.7874 0.4064)
			(end -0.7874 0.4064)
			(stroke
				(width 0.1524)
				(type default)
			)
			(layer "F.SilkS")
		)
		(fp_line
			(start -0.7874 0.4064)
			(end -0.7874 -0.4064)
			(stroke
				(width 0.1524)
				(type default)
			)
			(layer "F.SilkS")
		)
		(fp_line
			(start -0.12065 -0.305054)
			(end -0.12065 -0.2794)
			(stroke
				(width 0.1)
				(type default)
			)
			(layer "F.Fab")
		)
		(fp_line
			(start -0.67945 -0.305054)
			(end -0.12065 -0.305054)
			(stroke
				(width 0.1)
				(type default)
			)
			(layer "F.Fab")
		)
		(fp_line
			(start 0.67945 -0.3048)
			(end 0.67945 0.3048)
			(stroke
				(width 0.1)
				(type default)
			)
			(layer "F.Fab")
		)
		(fp_line
			(start 0.12065 -0.3048)
			(end 0.67945 -0.3048)
			(stroke
				(width 0.1)
				(type default)
			)
			(layer "F.Fab")
		)
		(fp_line
			(start 0.12065 -0.2794)
			(end 0.12065 -0.3048)
			(stroke
				(width 0.1)
				(type default)
			)
			(layer "F.Fab")
		)
		(fp_line
			(start -0.12065 -0.2794)
			(end 0.12065 -0.2794)
			(stroke
				(width 0.1)
				(type default)
			)
			(layer "F.Fab")
		)
		(fp_line
			(start 0.120396 0.2794)
			(end -0.12065 0.2794)
			(stroke
				(width 0.1)
				(type default)
			)
			(layer "F.Fab")
		)
		(fp_line
			(start -0.12065 0.2794)
			(end -0.12065 0.3048)
			(stroke
				(width 0.1)
				(type default)
			)
			(layer "F.Fab")
		)
		(fp_line
			(start 0.67945 0.3048)
			(end 0.120396 0.3048)
			(stroke
				(width 0.1)
				(type default)
			)
			(layer "F.Fab")
		)
		(fp_line
			(start 0.120396 0.3048)
			(end 0.120396 0.2794)
			(stroke
				(width 0.1)
				(type default)
			)
			(layer "F.Fab")
		)
		(fp_line
			(start -0.12065 0.3048)
			(end -0.67945 0.3048)
			(stroke
				(width 0.1)
				(type default)
			)
			(layer "F.Fab")
		)
		(fp_line
			(start -0.67945 0.3048)
			(end -0.67945 -0.305054)
			(stroke
				(width 0.1)
				(type default)
			)
			(layer "F.Fab")
		)
		(pad "1" smd circle
			(at -0.40005 0 90)
			(size 0 0)
			(layers "F.Cu" "F.Mask" "F.Paste")
			(net "P3V3_AUX")
		)
		(pad "2" smd circle
			(at 0.40005 0 90)
			(size 0 0)
			(layers "F.Cu" "F.Mask" "F.Paste")
			(net "UV_ADR_P2V5_COMP")
		)
	)
	(footprint ""
		(layer "F.Cu")
		(at 110.152942 -19.9898 90)
		(property "Reference" "R6273"
			(at 0 0 90)
			(layer "F.SilkS")
			(hide yes)
			(effects
				(font
					(size 1.27 1.27)
				)
			)
		)
		(property "Value" ""
			(at 0 0 90)
			(layer "F.Fab")
			(effects
				(font
					(size 1.27 1.27)
				)
			)
		)
		(duplicate_pad_numbers_are_jumpers no)
		(fp_line
			(start 0.7874 -0.4064)
			(end 0.7874 0.4064)
			(stroke
				(width 0.1524)
				(type default)
			)
			(layer "F.SilkS")
		)
		(fp_line
			(start -0.7874 -0.4064)
			(end 0.7874 -0.4064)
			(stroke
				(width 0.1524)
				(type default)
			)
			(layer "F.SilkS")
		)
		(fp_line
			(start 0.7874 0.4064)
			(end -0.7874 0.4064)
			(stroke
				(width 0.1524)
				(type default)
			)
			(layer "F.SilkS")
		)
		(fp_line
			(start -0.7874 0.4064)
			(end -0.7874 -0.4064)
			(stroke
				(width 0.1524)
				(type default)
			)
			(layer "F.SilkS")
		)
		(fp_line
			(start -0.12065 -0.305054)
			(end -0.12065 -0.2794)
			(stroke
				(width 0.1)
				(type default)
			)
			(layer "F.Fab")
		)
		(fp_line
			(start -0.67945 -0.305054)
			(end -0.12065 -0.305054)
			(stroke
				(width 0.1)
				(type default)
			)
			(layer "F.Fab")
		)
		(fp_line
			(start 0.67945 -0.3048)
			(end 0.67945 0.3048)
			(stroke
				(width 0.1)
				(type default)
			)
			(layer "F.Fab")
		)
		(fp_line
			(start 0.12065 -0.3048)
			(end 0.67945 -0.3048)
			(stroke
				(width 0.1)
				(type default)
			)
			(layer "F.Fab")
		)
		(fp_line
			(start 0.12065 -0.2794)
			(end 0.12065 -0.3048)
			(stroke
				(width 0.1)
				(type default)
			)
			(layer "F.Fab")
		)
		(fp_line
			(start -0.12065 -0.2794)
			(end 0.12065 -0.2794)
			(stroke
				(width 0.1)
				(type default)
			)
			(layer "F.Fab")
		)
		(fp_line
			(start 0.120396 0.2794)
			(end -0.12065 0.2794)
			(stroke
				(width 0.1)
				(type default)
			)
			(layer "F.Fab")
		)
		(fp_line
			(start -0.12065 0.2794)
			(end -0.12065 0.3048)
			(stroke
				(width 0.1)
				(type default)
			)
			(layer "F.Fab")
		)
		(fp_line
			(start 0.67945 0.3048)
			(end 0.120396 0.3048)
			(stroke
				(width 0.1)
				(type default)
			)
			(layer "F.Fab")
		)
		(fp_line
			(start 0.120396 0.3048)
			(end 0.120396 0.2794)
			(stroke
				(width 0.1)
				(type default)
			)
			(layer "F.Fab")
		)
		(fp_line
			(start -0.12065 0.3048)
			(end -0.67945 0.3048)
			(stroke
				(width 0.1)
				(type default)
			)
			(layer "F.Fab")
		)
		(fp_line
			(start -0.67945 0.3048)
			(end -0.67945 -0.305054)
			(stroke
				(width 0.1)
				(type default)
			)
			(layer "F.Fab")
		)
		(pad "1" smd circle
			(at -0.40005 0 90)
			(size 0 0)
			(layers "F.Cu" "F.Mask" "F.Paste")
			(net "P3V3_AUX")
		)
		(pad "2" smd circle
			(at 0.40005 0 90)
			(size 0 0)
			(layers "F.Cu" "F.Mask" "F.Paste")
			(net "USB_HUB2_MRP_CFG_STRAP")
		)
	)
)
